(kicad_pcb
	(version 20240108)
	(generator "pcbnew")
	(generator_version "8.0")
	(general
		(thickness 1.62)
		(legacy_teardrops no)
	)
	(paper "A4")
	(title_block
		(title "Jetson Orin Baseboard")
		(date "2025-03-12")
		(rev "1.3.4")
		(company "Antmicro Ltd")
		(comment 1 "www.antmicro.com")
		(comment 9 "footprints 532-535 of 677")
	)
	(layers
		(0 "F.Cu" signal)
		(1 "In1.Cu" signal)
		(2 "In2.Cu" signal)
		(3 "In3.Cu" signal)
		(4 "In4.Cu" jumper)
		(5 "In5.Cu" signal)
		(6 "In6.Cu" signal)
		(31 "B.Cu" signal)
		(32 "B.Adhes" user "B.Adhesive")
		(33 "F.Adhes" user "F.Adhesive")
		(34 "B.Paste" user)
		(35 "F.Paste" user)
		(36 "B.SilkS" user "B.Silkscreen")
		(37 "F.SilkS" user "F.Silkscreen")
		(38 "B.Mask" user)
		(39 "F.Mask" user)
		(40 "Dwgs.User" user "User.Drawings")
		(41 "Cmts.User" user "User.Comments")
		(42 "Eco1.User" user "User.Eco1")
		(43 "Eco2.User" user "User.Eco2")
		(44 "Edge.Cuts" user)
		(45 "Margin" user)
		(46 "B.CrtYd" user "B.Courtyard")
		(47 "F.CrtYd" user "F.Courtyard")
		(48 "B.Fab" user)
		(49 "F.Fab" user)
	)
	(footprint "antmicro-footprints:R_Array_4x0201_Panasonic_EXB18V"
		(layer "B.Cu")
		(at 107.89 98.24 90)
		(property "Reference" "R48"
			(at -1.06 1.51 -90)
			(layer "B.SilkS")
			(effects
				(font
					(size 0.7 0.7)
					(thickness 0.15)
				)
				(justify right bottom mirror)
			)
		)
		(property "Value" "R_4x2k2_0201_array"
			(at -1.1 -1.8 -90)
			(layer "B.Fab")
			(effects
				(font
					(size 0.7 0.7)
					(thickness 0.15)
				)
				(justify left bottom mirror)
			)
		)
		(property "Footprint" "antmicro-footprints:R_Array_4x0201_Panasonic_EXB18V"
			(at 0 0 90)
			(layer "F.Fab")
			(hide yes)
			(effects
				(font
					(size 1.27 1.27)
					(thickness 0.15)
				)
			)
		)
		(property "Datasheet" "http://industrial.panasonic.com/cdbs/www-data/pdf/AOC0000/AOC0000C14.pdf"
			(at 0 0 90)
			(layer "F.Fab")
			(hide yes)
			(effects
				(font
					(size 1.27 1.27)
					(thickness 0.15)
				)
			)
		)
		(property "Author" "Antmicro"
			(at 206.13 -9.65 0)
			(layer "B.Fab")
			(hide yes)
			(effects
				(font
					(size 1 1)
					(thickness 0.15)
				)
				(justify mirror)
			)
		)
		(property "License" "Apache-2.0"
			(at 206.13 -9.65 0)
			(layer "B.Fab")
			(hide yes)
			(effects
				(font
					(size 1 1)
					(thickness 0.15)
				)
				(justify mirror)
			)
		)
		(property "MPN" "EXB-18V222JX"
			(at 206.13 -9.65 0)
			(layer "B.Fab")
			(hide yes)
			(effects
				(font
					(size 1 1)
					(thickness 0.15)
				)
				(justify mirror)
			)
		)
		(property "Manufacturer" "Panasonic"
			(at 206.13 -9.65 0)
			(layer "B.Fab")
			(hide yes)
			(effects
				(font
					(size 1 1)
					(thickness 0.15)
				)
				(justify mirror)
			)
		)
		(property "Val" "4x2k2_0201"
			(at 206.13 -9.65 0)
			(layer "B.Fab")
			(hide yes)
			(effects
				(font
					(size 1 1)
					(thickness 0.15)
				)
				(justify mirror)
			)
		)
		(sheetname "CSI")
		(sheetfile "csi.kicad_sch")
		(attr smd)
		(fp_line
			(start 0.8 -0.45)
			(end 0.8 0.45)
			(stroke
				(width 0.12)
				(type solid)
			)
			(layer "B.SilkS")
		)
		(fp_line
			(start -0.8 -0.45)
			(end -0.8 0.45)
			(stroke
				(width 0.12)
				(type solid)
			)
			(layer "B.SilkS")
		)
		(fp_rect
			(start -0.898 0.66)
			(end 0.898 -0.65)
			(stroke
				(width 0.05)
				(type solid)
			)
			(fill none)
			(layer "B.CrtYd")
		)
		(fp_text user "${REFERENCE}"
			(at -1.051 -3.2 -90)
			(layer "B.Fab")
			(hide yes)
			(effects
				(font
					(size 0.7 0.7)
					(thickness 0.15)
				)
				(justify left bottom mirror)
			)
		)
		(fp_text user "Author: Antmicro"
			(at -1.051 -4.599 -90)
			(layer "B.Fab")
			(hide yes)
			(effects
				(font
					(size 0.7 0.7)
					(thickness 0.15)
				)
				(justify left bottom mirror)
			)
		)
		(fp_text user "License: Apache-2.0"
			(at -1.051 -6 -90)
			(layer "B.Fab")
			(hide yes)
			(effects
				(font
					(size 0.7 0.7)
					(thickness 0.15)
				)
				(justify left bottom mirror)
			)
		)
		(pad "1" smd roundrect
			(at -0.6 -0.298 90)
			(size 0.2 0.4)
			(layers "B.Cu" "B.Paste" "B.Mask")
			(roundrect_rratio 0.25)
			(net 337 "/CSI/SCL_CAM3")
			(pinfunction "R1.1")
			(pintype "passive")
		)
		(pad "2" smd roundrect
			(at -0.202 -0.298 90)
			(size 0.2 0.4)
			(layers "B.Cu" "B.Paste" "B.Mask")
			(roundrect_rratio 0.25)
			(net 336 "/CSI/SDA_CAM3")
			(pinfunction "R2.1")
			(pintype "passive")
		)
		(pad "3" smd roundrect
			(at 0.2 -0.298 90)
			(size 0.2 0.4)
			(layers "B.Cu" "B.Paste" "B.Mask")
			(roundrect_rratio 0.25)
			(net 333 "/CSI/SCL_CAM2")
			(pinfunction "R3.1")
			(pintype "passive")
		)
		(pad "4" smd roundrect
			(at 0.598 -0.298 90)
			(size 0.2 0.4)
			(layers "B.Cu" "B.Paste" "B.Mask")
			(roundrect_rratio 0.25)
			(net 331 "/CSI/SDA_CAM2")
			(pinfunction "R4.1")
			(pintype "passive")
		)
		(pad "5" smd roundrect
			(at 0.598 0.3 90)
			(size 0.2 0.4)
			(layers "B.Cu" "B.Paste" "B.Mask")
			(roundrect_rratio 0.25)
			(net 636 "/CSI/CSIB_I2C_VCC")
			(pinfunction "R4.2")
			(pintype "passive")
		)
		(pad "6" smd roundrect
			(at 0.2 0.3 90)
			(size 0.2 0.4)
			(layers "B.Cu" "B.Paste" "B.Mask")
			(roundrect_rratio 0.25)
			(net 636 "/CSI/CSIB_I2C_VCC")
			(pinfunction "R3.2")
			(pintype "passive")
		)
		(pad "7" smd roundrect
			(at -0.202 0.3 90)
			(size 0.2 0.4)
			(layers "B.Cu" "B.Paste" "B.Mask")
			(roundrect_rratio 0.25)
			(net 636 "/CSI/CSIB_I2C_VCC")
			(pinfunction "R2.2")
			(pintype "passive")
		)
		(pad "8" smd roundrect
			(at -0.6 0.3 90)
			(size 0.2 0.4)
			(layers "B.Cu" "B.Paste" "B.Mask")
			(roundrect_rratio 0.25)
			(net 636 "/CSI/CSIB_I2C_VCC")
			(pinfunction "R1.2")
			(pintype "passive")
		)
	)
	(footprint "antmicro-footprints:R_0402_1005Metric"
		(layer "B.Cu")
		(at 79.5 107.4)
		(descr "Resistor SMD 0402")
		(tags "resistor SMD 0402")
		(property "Reference" "R89"
			(at 3.3 2.34 180)
			(layer "B.SilkS")
			(effects
				(font
					(size 0.7 0.7)
					(thickness 0.15)
				)
				(justify left bottom mirror)
			)
		)
		(property "Value" "R_1k_0402"
			(at 0 -1.4 180)
			(layer "B.Fab")
			(effects
				(font
					(size 0.7 0.7)
					(thickness 0.15)
				)
				(justify left bottom mirror)
			)
		)
		(property "Footprint" "antmicro-footprints:R_0402_1005Metric"
			(at 0 0 0)
			(layer "F.Fab")
			(hide yes)
			(effects
				(font
					(size 1.27 1.27)
					(thickness 0.15)
				)
			)
		)
		(property "Datasheet" "https://www.bourns.com/docs/product-datasheets/cr.pdf"
			(at 0 0 0)
			(layer "F.Fab")
			(hide yes)
			(effects
				(font
					(size 1.27 1.27)
					(thickness 0.15)
				)
			)
		)
		(property "Author" "Antmicro"
			(at 0 0 0)
			(layer "B.Fab")
			(hide yes)
			(effects
				(font
					(size 1 1)
					(thickness 0.15)
				)
				(justify mirror)
			)
		)
		(property "License" "Apache-2.0"
			(at 0 0 0)
			(layer "B.Fab")
			(hide yes)
			(effects
				(font
					(size 1 1)
					(thickness 0.15)
				)
				(justify mirror)
			)
		)
		(property "MPN" "CR0402-FX-1001GLF"
			(at 0 0 0)
			(layer "B.Fab")
			(hide yes)
			(effects
				(font
					(size 1 1)
					(thickness 0.15)
				)
				(justify mirror)
			)
		)
		(property "Manufacturer" "Bourns"
			(at 0 0 0)
			(layer "B.Fab")
			(hide yes)
			(effects
				(font
					(size 1 1)
					(thickness 0.15)
				)
				(justify mirror)
			)
		)
		(property "Tolerance" "1%"
			(at 0 0 0)
			(layer "B.Fab")
			(hide yes)
			(effects
				(font
					(size 1 1)
					(thickness 0.15)
				)
				(justify mirror)
			)
		)
		(property "Val" "1k"
			(at 0 0 0)
			(layer "B.Fab")
			(hide yes)
			(effects
				(font
					(size 1 1)
					(thickness 0.15)
				)
				(justify mirror)
			)
		)
		(sheetname "USB Debug, DP")
		(sheetfile "usb.kicad_sch")
		(attr smd exclude_from_pos_files exclude_from_bom dnp)
		(fp_rect
			(start -0.925 0.47)
			(end 0.925 -0.47)
			(stroke
				(width 0.05)
				(type default)
			)
			(fill none)
			(layer "B.CrtYd")
		)
		(fp_rect
			(start -0.5 0.25)
			(end 0.5 -0.25)
			(stroke
				(width 0.15)
				(type solid)
			)
			(fill none)
			(layer "B.Fab")
		)
		(fp_text user "${REFERENCE}"
			(at -0.95 -3.168 180)
			(layer "B.Fab")
			(hide yes)
			(effects
				(font
					(size 0.7 0.7)
					(thickness 0.15)
				)
				(justify left bottom mirror)
			)
		)
		(fp_text user "License: Apache-2.0"
			(at -0.95 -5.169 180)
			(layer "B.Fab")
			(hide yes)
			(effects
				(font
					(size 0.7 0.7)
					(thickness 0.15)
				)
				(justify left bottom mirror)
			)
		)
		(fp_text user "Author: Antmicro"
			(at -0.95 -4.169 180)
			(layer "B.Fab")
			(hide yes)
			(effects
				(font
					(size 0.7 0.7)
					(thickness 0.15)
				)
				(justify left bottom mirror)
			)
		)
		(pad "1" smd roundrect
			(at -0.48 0)
			(size 0.59 0.64)
			(layers "B.Cu" "B.Paste" "B.Mask")
			(roundrect_rratio 0.25)
			(net 306 "/USB Debug, DP/USBC0_SSEQ1")
			(pintype "passive")
		)
		(pad "2" smd roundrect
			(at 0.48 0)
			(size 0.59 0.64)
			(layers "B.Cu" "B.Paste" "B.Mask")
			(roundrect_rratio 0.25)
			(net 87 "+3V3")
			(pintype "passive")
		)
	)
	(footprint "antmicro-footprints:R_0402_1005Metric"
		(layer "B.Cu")
		(at 92.35 115.2 -90)
		(descr "Resistor SMD 0402")
		(tags "resistor SMD 0402")
		(property "Reference" "R83"
			(at -1.12 -1.33 90)
			(layer "B.SilkS")
			(effects
				(font
					(size 0.7 0.7)
					(thickness 0.15)
				)
				(justify left bottom mirror)
			)
		)
		(property "Value" "R_10k_0402"
			(at 0 -1.4 90)
			(layer "B.Fab")
			(effects
				(font
					(size 0.7 0.7)
					(thickness 0.15)
				)
				(justify left bottom mirror)
			)
		)
		(property "Footprint" "antmicro-footprints:R_0402_1005Metric"
			(at 0 0 -90)
			(layer "F.Fab")
			(hide yes)
			(effects
				(font
					(size 1.27 1.27)
					(thickness 0.15)
				)
			)
		)
		(property "Datasheet" "https://www.bourns.com/docs/product-datasheets/cr.pdf"
			(at 0 0 -90)
			(layer "F.Fab")
			(hide yes)
			(effects
				(font
					(size 1.27 1.27)
					(thickness 0.15)
				)
			)
		)
		(property "Author" "Antmicro"
			(at -22.85 207.55 0)
			(layer "B.Fab")
			(hide yes)
			(effects
				(font
					(size 1 1)
					(thickness 0.15)
				)
				(justify mirror)
			)
		)
		(property "License" "Apache-2.0"
			(at -22.85 207.55 0)
			(layer "B.Fab")
			(hide yes)
			(effects
				(font
					(size 1 1)
					(thickness 0.15)
				)
				(justify mirror)
			)
		)
		(property "MPN" "CR0402-FX-1002GLF"
			(at -22.85 207.55 0)
			(layer "B.Fab")
			(hide yes)
			(effects
				(font
					(size 1 1)
					(thickness 0.15)
				)
				(justify mirror)
			)
		)
		(property "Manufacturer" "Bourns"
			(at -22.85 207.55 0)
			(layer "B.Fab")
			(hide yes)
			(effects
				(font
					(size 1 1)
					(thickness 0.15)
				)
				(justify mirror)
			)
		)
		(property "Tolerance" "1%"
			(at -22.85 207.55 0)
			(layer "B.Fab")
			(hide yes)
			(effects
				(font
					(size 1 1)
					(thickness 0.15)
				)
				(justify mirror)
			)
		)
		(property "Val" "10k"
			(at -22.85 207.55 0)
			(layer "B.Fab")
			(hide yes)
			(effects
				(font
					(size 1 1)
					(thickness 0.15)
				)
				(justify mirror)
			)
		)
		(sheetname "USB Debug, DP")
		(sheetfile "usb.kicad_sch")
		(attr smd)
		(fp_rect
			(start -0.925 0.47)
			(end 0.925 -0.47)
			(stroke
				(width 0.05)
				(type default)
			)
			(fill none)
			(layer "B.CrtYd")
		)
		(fp_rect
			(start -0.5 0.25)
			(end 0.5 -0.25)
			(stroke
				(width 0.15)
				(type solid)
			)
			(fill none)
			(layer "B.Fab")
		)
		(fp_text user "License: Apache-2.0"
			(at -0.95 -5.169 90)
			(layer "B.Fab")
			(hide yes)
			(effects
				(font
					(size 0.7 0.7)
					(thickness 0.15)
				)
				(justify left bottom mirror)
			)
		)
		(fp_text user "Author: Antmicro"
			(at -0.95 -4.169 90)
			(layer "B.Fab")
			(hide yes)
			(effects
				(font
					(size 0.7 0.7)
					(thickness 0.15)
				)
				(justify left bottom mirror)
			)
		)
		(fp_text user "${REFERENCE}"
			(at -0.95 -3.168 90)
			(layer "B.Fab")
			(hide yes)
			(effects
				(font
					(size 0.7 0.7)
					(thickness 0.15)
				)
				(justify left bottom mirror)
			)
		)
		(pad "1" smd roundrect
			(at -0.48 0 270)
			(size 0.59 0.64)
			(layers "B.Cu" "B.Paste" "B.Mask")
			(roundrect_rratio 0.25)
			(net 505 "USBC0_FLG")
			(pintype "passive")
		)
		(pad "2" smd roundrect
			(at 0.48 0 270)
			(size 0.59 0.64)
			(layers "B.Cu" "B.Paste" "B.Mask")
			(roundrect_rratio 0.25)
			(net 87 "+3V3")
			(pintype "passive")
		)
	)
	(footprint "antmicro-footprints:R_0402_1005Metric"
		(layer "B.Cu")
		(at 75 105.3 -90)
		(descr "Resistor SMD 0402")
		(tags "resistor SMD 0402")
		(property "Reference" "R92"
			(at -5.03 -1.69 90)
			(layer "B.SilkS")
			(effects
				(font
					(size 0.7 0.7)
					(thickness 0.15)
				)
				(justify left bottom mirror)
			)
		)
		(property "Value" "R_1k_0402"
			(at 0 -1.4 90)
			(layer "B.Fab")
			(effects
				(font
					(size 0.7 0.7)
					(thickness 0.15)
				)
				(justify left bottom mirror)
			)
		)
		(property "Footprint" "antmicro-footprints:R_0402_1005Metric"
			(at 0 0 -90)
			(layer "F.Fab")
			(hide yes)
			(effects
				(font
					(size 1.27 1.27)
					(thickness 0.15)
				)
			)
		)
		(property "Datasheet" "https://www.bourns.com/docs/product-datasheets/cr.pdf"
			(at 0 0 -90)
			(layer "F.Fab")
			(hide yes)
			(effects
				(font
					(size 1.27 1.27)
					(thickness 0.15)
				)
			)
		)
		(property "Author" "Antmicro"
			(at -30.3 180.3 0)
			(layer "B.Fab")
			(hide yes)
			(effects
				(font
					(size 1 1)
					(thickness 0.15)
				)
				(justify mirror)
			)
		)
		(property "License" "Apache-2.0"
			(at -30.3 180.3 0)
			(layer "B.Fab")
			(hide yes)
			(effects
				(font
					(size 1 1)
					(thickness 0.15)
				)
				(justify mirror)
			)
		)
		(property "MPN" "CR0402-FX-1001GLF"
			(at -30.3 180.3 0)
			(layer "B.Fab")
			(hide yes)
			(effects
				(font
					(size 1 1)
					(thickness 0.15)
				)
				(justify mirror)
			)
		)
		(property "Manufacturer" "Bourns"
			(at -30.3 180.3 0)
			(layer "B.Fab")
			(hide yes)
			(effects
				(font
					(size 1 1)
					(thickness 0.15)
				)
				(justify mirror)
			)
		)
		(property "Tolerance" "1%"
			(at -30.3 180.3 0)
			(layer "B.Fab")
			(hide yes)
			(effects
				(font
					(size 1 1)
					(thickness 0.15)
				)
				(justify mirror)
			)
		)
		(property "Val" "1k"
			(at -30.3 180.3 0)
			(layer "B.Fab")
			(hide yes)
			(effects
				(font
					(size 1 1)
					(thickness 0.15)
				)
				(justify mirror)
			)
		)
		(sheetname "USB Debug, DP")
		(sheetfile "usb.kicad_sch")
		(attr smd exclude_from_pos_files exclude_from_bom dnp)
		(fp_rect
			(start -0.925 0.47)
			(end 0.925 -0.47)
			(stroke
				(width 0.05)
				(type default)
			)
			(fill none)
			(layer "B.CrtYd")
		)
		(fp_rect
			(start -0.5 0.25)
			(end 0.5 -0.25)
			(stroke
				(width 0.15)
				(type solid)
			)
			(fill none)
			(layer "B.Fab")
		)
		(fp_text user "Author: Antmicro"
			(at -0.95 -4.169 90)
			(layer "B.Fab")
			(hide yes)
			(effects
				(font
					(size 0.7 0.7)
					(thickness 0.15)
				)
				(justify left bottom mirror)
			)
		)
		(fp_text user "License: Apache-2.0"
			(at -0.95 -5.169 90)
			(layer "B.Fab")
			(hide yes)
			(effects
				(font
					(size 0.7 0.7)
					(thickness 0.15)
				)
				(justify left bottom mirror)
			)
		)
		(fp_text user "${REFERENCE}"
			(at -0.95 -3.168 90)
			(layer "B.Fab")
			(hide yes)
			(effects
				(font
					(size 0.7 0.7)
					(thickness 0.15)
				)
				(justify left bottom mirror)
			)
		)
		(pad "1" smd roundrect
			(at -0.48 0 270)
			(size 0.59 0.64)
			(layers "B.Cu" "B.Paste" "B.Mask")
			(roundrect_rratio 0.25)
			(net 307 "/USB Debug, DP/USBC0_DPEQ0")
			(pintype "passive")
		)
		(pad "2" smd roundrect
			(at 0.48 0 270)
			(size 0.59 0.64)
			(layers "B.Cu" "B.Paste" "B.Mask")
			(roundrect_rratio 0.25)
			(net 1 "GND")
			(pintype "passive")
		)
	)
)
